(kicad_pcb
	(version 20260206)
	(generator "pcbnew")
	(generator_version "10.0")
	(general
		(thickness 1.6)
		(legacy_teardrops no)
	)
	(paper "A4")
	(title_block
		(title "m-2 — Lightning_M.2_BRD.brd")
		(comment 1 "Lightning (Wiwynn / Facebook NVMe JBOF) / footprints 39-45 of 157")
	)
	(layers
		(0 "F.Cu" signal "TOP")
		(4 "In1.Cu" signal "L2GND")
		(6 "In2.Cu" signal "L3")
		(8 "In3.Cu" signal "L4GND")
		(10 "In4.Cu" signal "L5GND")
		(12 "In5.Cu" signal "L6")
		(14 "In6.Cu" signal "L7GND")
		(2 "B.Cu" signal "BOTTOM")
		(9 "F.Adhes" user "F.Adhesive")
		(11 "B.Adhes" user "B.Adhesive")
		(13 "F.Paste" user "Package Geometry/Pastemask Top")
		(15 "B.Paste" user "Package Geometry/Pastemask Bottom")
		(5 "F.SilkS" user "Ref Des/Silkscreen Top")
		(7 "B.SilkS" user "Ref Des/Silkscreen Bottom")
		(1 "F.Mask" user "Board Geometry/Soldermask Top")
		(3 "B.Mask" user "Board Geometry/Soldermask Bottom")
		(17 "Dwgs.User" user "User.Drawings")
		(19 "Cmts.User" user "User.Comments")
		(21 "Eco1.User" user "User.Eco1")
		(23 "Eco2.User" user "User.Eco2")
		(25 "Edge.Cuts" user "Board Geometry/Outline")
		(27 "Margin" user)
		(31 "F.CrtYd" user "Package Geometry/Place Bound Top")
		(29 "B.CrtYd" user "Package Geometry/Place Bound Bottom")
		(35 "F.Fab" user "Ref Des/Assembly Top")
		(33 "B.Fab" user "Ref Des/Assembly Bottom")
	)
	(footprint ""
		(layer "F.Cu")
		(at 35.306 -80.264 180)
		(property "Reference" "PL2"
			(at 0 0 180)
			(layer "F.SilkS")
			(hide yes)
			(effects
				(font
					(size 1.27 1.27)
				)
			)
		)
		(property "Value" "BLM21PG220SN1DGP"
			(at 0.0254 -5.6896 180)
			(unlocked yes)
			(layer "F.Fab")
			(hide yes)
			(effects
				(font
					(size 1.016 1.016)
					(thickness 0.1524)
				)
			)
		)
		(property "Device Type" "L20125H42"
			(at 0.0254 -7.5946 180)
			(unlocked yes)
			(layer "F.Fab")
			(hide yes)
			(effects
				(font
					(size 1.016 1.016)
					(thickness 0.1524)
				)
			)
		)
		(duplicate_pad_numbers_are_jumpers no)
		(fp_line
			(start 0.9144 1.7018)
			(end 0.9144 -1.7018)
			(stroke
				(width 0.1524)
				(type default)
			)
			(layer "F.SilkS")
		)
		(fp_line
			(start 0.9144 -1.7018)
			(end -0.9144 -1.7018)
			(stroke
				(width 0.1524)
				(type default)
			)
			(layer "F.SilkS")
		)
		(fp_line
			(start -0.9144 1.7018)
			(end 0.9144 1.7018)
			(stroke
				(width 0.1524)
				(type default)
			)
			(layer "F.SilkS")
		)
		(fp_line
			(start -0.9144 -1.7018)
			(end -0.9144 1.7018)
			(stroke
				(width 0.1524)
				(type default)
			)
			(layer "F.SilkS")
		)
		(fp_rect
			(start -1.0033 1.778)
			(end 1.0033 -1.778)
			(stroke
				(width 0)
				(type default)
			)
			(fill no)
			(layer "F.CrtYd")
		)
		(fp_poly
			(pts
				(xy -1.0033 -1.778) (xy 1.0033 -1.778) (xy 1.0033 1.778) (xy -1.0033 1.778)
			)
			(stroke
				(width 0)
				(type default)
			)
			(fill no)
			(layer "F.Fab")
		)
		(pad "1" smd rect
			(at 0 -0.9652 180)
			(size 1.397 1.143)
			(layers "F.Cu" "F.Mask" "F.Paste")
			(net "P12V")
		)
		(pad "2" smd rect
			(at 0 0.9652 180)
			(size 1.397 1.143)
			(layers "F.Cu" "F.Mask" "F.Paste")
			(net "P3V3_DEV_VIN")
		)
	)
	(footprint ""
		(layer "F.Cu")
		(at 60.579 -40.259 90)
		(property "Reference" "U1"
			(at 0 0 90)
			(layer "F.SilkS")
			(hide yes)
			(effects
				(font
					(size 1.27 1.27)
				)
			)
		)
		(property "Value" "TMP75AIDGKR-GP"
			(at -0.1143 -9.1948 90)
			(unlocked yes)
			(layer "F.Fab")
			(hide yes)
			(effects
				(font
					(size 1.016 1.016)
					(thickness 0.1524)
				)
			)
		)
		(property "Device Type" "MSOP8-1H44"
			(at -0.1143 -10.795 90)
			(unlocked yes)
			(layer "F.Fab")
			(hide yes)
			(effects
				(font
					(size 1.016 1.016)
					(thickness 0.1524)
				)
			)
		)
		(duplicate_pad_numbers_are_jumpers no)
		(fp_line
			(start 1.0795 -1.016)
			(end -1.9558 -1.016)
			(stroke
				(width 0.1524)
				(type default)
			)
			(layer "F.SilkS")
		)
		(fp_line
			(start -1.9558 -1.016)
			(end -1.9558 1.016)
			(stroke
				(width 0.1524)
				(type default)
			)
			(layer "F.SilkS")
		)
		(fp_line
			(start -1.9558 -0.5461)
			(end -1.4478 -0.0381)
			(stroke
				(width 0.1524)
				(type default)
			)
			(layer "F.SilkS")
		)
		(fp_line
			(start -1.4478 -0.0381)
			(end -1.9558 0.4699)
			(stroke
				(width 0.1524)
				(type default)
			)
			(layer "F.SilkS")
		)
		(fp_line
			(start 1.0795 1.016)
			(end 1.0795 -1.016)
			(stroke
				(width 0.1524)
				(type default)
			)
			(layer "F.SilkS")
		)
		(fp_line
			(start -1.9558 1.016)
			(end 1.0795 1.016)
			(stroke
				(width 0.1524)
				(type default)
			)
			(layer "F.SilkS")
		)
		(fp_line
			(start -1.778 1.0922)
			(end -1.778 3.048)
			(stroke
				(width 0.508)
				(type default)
			)
			(layer "F.SilkS")
		)
		(fp_poly
			(pts
				(xy -1.1557 -1.016) (xy -1.1557 1.016) (xy 1.1557 1.016) (xy 1.1557 -1.016)
			)
			(stroke
				(width 0)
				(type default)
			)
			(fill yes)
			(layer "F.SilkS")
		)
		(fp_rect
			(start -1.4986 2.4511)
			(end 1.4986 -2.4511)
			(stroke
				(width 0)
				(type default)
			)
			(fill no)
			(layer "F.CrtYd")
		)
		(fp_poly
			(pts
				(xy -2.032 3.302) (xy -2.032 -3.302) (xy 2.032 -3.302) (xy 2.032 -2.1209) (xy 1.4986 -2.1209) (xy 1.4986 -2.4511)
				(xy -1.4986 -2.4511) (xy -1.4986 2.4511) (xy 1.4986 2.4511) (xy 1.4986 -2.1082) (xy 2.032 -2.1082)
				(xy 2.032 3.302)
			)
			(stroke
				(width 0)
				(type default)
			)
			(fill no)
			(layer "F.CrtYd")
		)
		(fp_rect
			(start -2.032 3.302)
			(end 2.032 -3.302)
			(stroke
				(width 0)
				(type default)
			)
			(fill no)
			(layer "F.Fab")
		)
		(pad "1" smd rect
			(at -0.97536 2.05486 90)
			(size 0.3556 1.524)
			(layers "F.Cu" "F.Mask" "F.Paste")
			(net "Z50_TEMP_1_DATA")
		)
		(pad "2" smd rect
			(at -0.32512 2.05486 90)
			(size 0.3556 1.524)
			(layers "F.Cu" "F.Mask" "F.Paste")
			(net "Z50_TEMP_1_CLK")
		)
		(pad "3" smd rect
			(at 0.32512 2.05486 90)
			(size 0.3556 1.524)
			(layers "F.Cu" "F.Mask" "F.Paste")
			(net "Z50_TEMP_1_ALERT#")
		)
		(pad "4" smd rect
			(at 0.97536 2.05486 90)
			(size 0.3556 1.524)
			(layers "F.Cu" "F.Mask" "F.Paste")
			(net "GND")
		)
		(pad "5" smd rect
			(at 0.97536 -2.05486 90)
			(size 0.3556 1.524)
			(layers "F.Cu" "F.Mask" "F.Paste")
			(net "Z50_TEMP_1_A2")
		)
		(pad "6" smd rect
			(at 0.32512 -2.05486 90)
			(size 0.3556 1.524)
			(layers "F.Cu" "F.Mask" "F.Paste")
			(net "Z50_TEMP_1_A1")
		)
		(pad "7" smd rect
			(at -0.32512 -2.05486 90)
			(size 0.3556 1.524)
			(layers "F.Cu" "F.Mask" "F.Paste")
			(net "Z50_TEMP_1_A0")
		)
		(pad "8" smd rect
			(at -0.97536 -2.05486 90)
			(size 0.3556 1.524)
			(layers "F.Cu" "F.Mask" "F.Paste")
			(net "P3V3_DPB")
		)
	)
	(footprint ""
		(layer "F.Cu")
		(at 35.306 -84.582 180)
		(property "Reference" "PC35"
			(at 0 0 180)
			(layer "F.SilkS")
			(hide yes)
			(effects
				(font
					(size 1.27 1.27)
				)
			)
		)
		(property "Value" "SC10U16V5KX-1-GP"
			(at -0.0762 -6.1214 180)
			(unlocked yes)
			(layer "F.Fab")
			(hide yes)
			(effects
				(font
					(size 1.016 1.016)
					(thickness 0.1524)
				)
			)
		)
		(property "Device Type" "C805H54"
			(at -0.0762 -8.1534 180)
			(unlocked yes)
			(layer "F.Fab")
			(hide yes)
			(effects
				(font
					(size 1.016 1.016)
					(thickness 0.1524)
				)
			)
		)
		(duplicate_pad_numbers_are_jumpers no)
		(fp_line
			(start 0.635 0)
			(end -0.635 0)
			(stroke
				(width 0.508)
				(type default)
			)
			(layer "F.SilkS")
		)
		(fp_rect
			(start -0.9652 1.778)
			(end 0.9652 -1.778)
			(stroke
				(width 0)
				(type default)
			)
			(fill no)
			(layer "F.CrtYd")
		)
		(fp_poly
			(pts
				(xy -0.9652 -1.778) (xy 0.9652 -1.778) (xy 0.9652 1.778) (xy -0.9652 1.778)
			)
			(stroke
				(width 0)
				(type default)
			)
			(fill no)
			(layer "F.Fab")
		)
		(pad "1" smd rect
			(at 0 -0.9652 180)
			(size 1.397 1.143)
			(layers "F.Cu" "F.Mask" "F.Paste")
			(net "P3V3_DEV_VIN")
		)
		(pad "2" smd rect
			(at 0 0.9652 180)
			(size 1.397 1.143)
			(layers "F.Cu" "F.Mask" "F.Paste")
			(net "GND")
		)
	)
	(footprint ""
		(layer "F.Cu")
		(at 29.21 -84.122006)
		(property "Reference" "U4"
			(at 0 0 0)
			(layer "F.SilkS")
			(hide yes)
			(effects
				(font
					(size 1.27 1.27)
				)
			)
		)
		(property "Value" "PCA9543APW-GP"
			(at 0.1016 -7.62 0)
			(unlocked yes)
			(layer "F.Fab")
			(hide yes)
			(effects
				(font
					(size 1.016 1.016)
					(thickness 0.1524)
				)
			)
		)
		(property "Device Type" "TSOIC14H44"
			(at 0.1016 -10.16 0)
			(unlocked yes)
			(layer "F.Fab")
			(hide yes)
			(effects
				(font
					(size 1.016 1.016)
					(thickness 0.1524)
				)
			)
		)
		(duplicate_pad_numbers_are_jumpers no)
		(fp_line
			(start -3.048 -1.778)
			(end -3.048 4.191)
			(stroke
				(width 0.2032)
				(type default)
			)
			(layer "F.SilkS")
		)
		(fp_line
			(start -3.048 -1.778)
			(end 2.159 -1.778)
			(stroke
				(width 0.2032)
				(type default)
			)
			(layer "F.SilkS")
		)
		(fp_line
			(start -3.048 4.191)
			(end -3.048 1.397)
			(stroke
				(width 0.508)
				(type default)
			)
			(layer "F.SilkS")
		)
		(fp_line
			(start -2.032 0)
			(end -3.048 -1.016)
			(stroke
				(width 0.2032)
				(type default)
			)
			(layer "F.SilkS")
		)
		(fp_line
			(start -2.032 0)
			(end -3.048 1.016)
			(stroke
				(width 0.2032)
				(type default)
			)
			(layer "F.SilkS")
		)
		(fp_line
			(start 2.159 -1.778)
			(end 2.159 1.778)
			(stroke
				(width 0.2032)
				(type default)
			)
			(layer "F.SilkS")
		)
		(fp_line
			(start 2.159 1.7526)
			(end -3.0734 1.7526)
			(stroke
				(width 0.2032)
				(type default)
			)
			(layer "F.SilkS")
		)
		(fp_line
			(start 2.159 1.778)
			(end 2.159 1.7526)
			(stroke
				(width 0.2032)
				(type default)
			)
			(layer "F.SilkS")
		)
		(fp_poly
			(pts
				(xy -2.2606 -1.8542) (xy 2.2606 -1.8542) (xy 2.2606 1.8542) (xy -2.2606 1.8542)
			)
			(stroke
				(width 0)
				(type default)
			)
			(fill yes)
			(layer "F.SilkS")
		)
		(fp_poly
			(pts
				(xy -3.048 -4.0894) (xy 3.048 -4.0894) (xy 3.048 4.0894) (xy -3.048 4.0894)
			)
			(stroke
				(width 0)
				(type default)
			)
			(fill no)
			(layer "F.CrtYd")
		)
		(fp_poly
			(pts
				(xy -3.048 -4.0894) (xy 3.048 -4.0894) (xy 3.048 4.0894) (xy -3.048 4.0894)
			)
			(stroke
				(width 0)
				(type default)
			)
			(fill no)
			(layer "F.Fab")
		)
		(pad "1" smd rect
			(at -1.94945 2.8194)
			(size 0.3556 1.524)
			(layers "F.Cu" "F.Mask" "F.Paste")
			(net "Z50_SMB_SWITCH_ADDRESS_A0")
		)
		(pad "2" smd rect
			(at -1.30048 2.8194)
			(size 0.3556 1.524)
			(layers "F.Cu" "F.Mask" "F.Paste")
			(net "Z50_SMB_SWITCH_ADDRESS_A1")
		)
		(pad "3" smd rect
			(at -0.65024 2.8194)
			(size 0.3556 1.524)
			(layers "F.Cu" "F.Mask" "F.Paste")
			(net "Z50_SMB_SWITCH_RESET#")
		)
		(pad "4" smd rect
			(at 0 2.8194)
			(size 0.3556 1.524)
			(layers "F.Cu" "F.Mask" "F.Paste")
			(net "Net_14")
		)
		(pad "5" smd rect
			(at 0.65024 2.8194)
			(size 0.3556 1.524)
			(layers "F.Cu" "F.Mask" "F.Paste")
			(net "Z50_SSD_A1_SMB_DATA_R")
		)
		(pad "6" smd rect
			(at 1.30048 2.8194)
			(size 0.3556 1.524)
			(layers "F.Cu" "F.Mask" "F.Paste")
			(net "Z50_SSD_A1_SMB_CLK_R")
		)
		(pad "7" smd rect
			(at 1.94945 2.8194)
			(size 0.3556 1.524)
			(layers "F.Cu" "F.Mask" "F.Paste")
			(net "GND")
		)
		(pad "8" smd rect
			(at 1.94945 -2.8194)
			(size 0.3556 1.524)
			(layers "F.Cu" "F.Mask" "F.Paste")
			(net "Net_13")
		)
		(pad "9" smd rect
			(at 1.30048 -2.8194)
			(size 0.3556 1.524)
			(layers "F.Cu" "F.Mask" "F.Paste")
			(net "Z50_SSD_B1_SMB_DATA_R")
		)
		(pad "10" smd rect
			(at 0.65024 -2.8194)
			(size 0.3556 1.524)
			(layers "F.Cu" "F.Mask" "F.Paste")
			(net "Z50_SSD_B1_SMB_CLK_R")
		)
		(pad "11" smd rect
			(at 0 -2.8194)
			(size 0.3556 1.524)
			(layers "F.Cu" "F.Mask" "F.Paste")
			(net "Net_12")
		)
		(pad "12" smd rect
			(at -0.65024 -2.8194)
			(size 0.3556 1.524)
			(layers "F.Cu" "F.Mask" "F.Paste")
			(net "Z50_SMB_CLK")
		)
		(pad "13" smd rect
			(at -1.30048 -2.8194)
			(size 0.3556 1.524)
			(layers "F.Cu" "F.Mask" "F.Paste")
			(net "Z50_SMB_DATA")
		)
		(pad "14" smd rect
			(at -1.94945 -2.8194)
			(size 0.3556 1.524)
			(layers "F.Cu" "F.Mask" "F.Paste")
			(net "P3V3_DPB")
		)
	)
	(footprint ""
		(layer "F.Cu")
		(at 24.13 -71.755)
		(property "Reference" "R56"
			(at 0 0 0)
			(layer "F.SilkS")
			(hide yes)
			(effects
				(font
					(size 1.27 1.27)
				)
			)
		)
		(property "Value" "33R2J-2-GP"
			(at 0.064008 -3.993896 0)
			(unlocked yes)
			(layer "F.Fab")
			(hide yes)
			(effects
				(font
					(size 1.016 1.016)
					(thickness 0.1524)
				)
			)
		)
		(property "Device Type" "R402H16"
			(at 0.064008 -5.517896 0)
			(unlocked yes)
			(layer "F.Fab")
			(hide yes)
			(effects
				(font
					(size 1.016 1.016)
					(thickness 0.1524)
				)
			)
		)
		(duplicate_pad_numbers_are_jumpers no)
		(fp_line
			(start -0.508 -0.9398)
			(end -0.508 0.9398)
			(stroke
				(width 0.1524)
				(type default)
			)
			(layer "F.SilkS")
		)
		(fp_line
			(start 0.508 -0.9398)
			(end -0.508 -0.9398)
			(stroke
				(width 0.1524)
				(type default)
			)
			(layer "F.SilkS")
		)
		(fp_rect
			(start -0.508 0.9398)
			(end 0.508 -0.9398)
			(stroke
				(width 0)
				(type default)
			)
			(fill no)
			(layer "F.CrtYd")
		)
		(fp_rect
			(start -0.508 0.9398)
			(end 0.508 -0.9398)
			(stroke
				(width 0)
				(type default)
			)
			(fill no)
			(layer "F.Fab")
		)
		(pad "1" smd custom
			(at 0 -0.4445)
			(size 0.1397 0.1397)
			(layers "F.Cu" "F.Mask" "F.Paste")
			(net "Z50_SSD_A1_SMB_CLK_LR")
			(options
				(clearance outline)
				(anchor circle)
			)
			(primitives
				(gr_poly
					(pts
						(arc
							(start -0.1778 -0.2794)
							(mid -0.249642 -0.249642)
							(end -0.2794 -0.1778)
						)
						(arc
							(start -0.2794 0.1778)
							(mid -0.249642 0.249642)
							(end -0.1778 0.2794)
						)
						(arc
							(start 0.1778 0.2794)
							(mid 0.249642 0.249642)
							(end 0.2794 0.1778)
						)
						(arc
							(start 0.2794 -0.1778)
							(mid 0.249642 -0.249642)
							(end 0.1778 -0.2794)
						)
					)
					(width 0)
					(fill yes)
				)
			)
		)
		(pad "2" smd custom
			(at 0 0.4445)
			(size 0.1397 0.1397)
			(layers "F.Cu" "F.Mask" "F.Paste")
			(net "Z50_SSD_A1_SMB_CLK")
			(options
				(clearance outline)
				(anchor circle)
			)
			(primitives
				(gr_poly
					(pts
						(arc
							(start -0.1778 -0.2794)
							(mid -0.249642 -0.249642)
							(end -0.2794 -0.1778)
						)
						(arc
							(start -0.2794 0.1778)
							(mid -0.249642 0.249642)
							(end -0.1778 0.2794)
						)
						(arc
							(start 0.1778 0.2794)
							(mid 0.249642 0.249642)
							(end 0.2794 0.1778)
						)
						(arc
							(start 0.2794 -0.1778)
							(mid 0.249642 -0.249642)
							(end 0.1778 -0.2794)
						)
					)
					(width 0)
					(fill yes)
				)
			)
		)
	)
	(footprint ""
		(layer "F.Cu")
		(at 59.817 -45.593 -90)
		(property "Reference" "C3"
			(at 0 0 270)
			(layer "F.SilkS")
			(hide yes)
			(effects
				(font
					(size 1.27 1.27)
				)
			)
		)
		(property "Value" "SCD1U16V2KX-3GP"
			(at 1.1811 -2.7051 270)
			(unlocked yes)
			(layer "F.Fab")
			(hide yes)
			(effects
				(font
					(size 1.016 1.016)
					(thickness 0.1524)
				)
			)
		)
		(property "Device Type" "C402H22"
			(at 1.1811 -4.2291 270)
			(unlocked yes)
			(layer "F.Fab")
			(hide yes)
			(effects
				(font
					(size 1.016 1.016)
					(thickness 0.1524)
				)
			)
		)
		(duplicate_pad_numbers_are_jumpers no)
		(fp_rect
			(start -0.4318 0.9525)
			(end 0.4318 -0.9525)
			(stroke
				(width 0)
				(type default)
			)
			(fill no)
			(layer "F.CrtYd")
		)
		(fp_rect
			(start -0.4318 0.9525)
			(end 0.4318 -0.9525)
			(stroke
				(width 0)
				(type default)
			)
			(fill no)
			(layer "F.Fab")
		)
		(pad "1" smd custom
			(at 0 -0.4445 270)
			(size 0.1524 0.1524)
			(layers "F.Cu" "F.Mask" "F.Paste")
			(net "P3V3_PWR")
			(options
				(clearance outline)
				(anchor circle)
			)
			(primitives
				(gr_poly
					(pts
						(arc
							(start 0.3048 -0.2032)
							(mid 0.275042 -0.275042)
							(end 0.2032 -0.3048)
						)
						(arc
							(start -0.2032 -0.3048)
							(mid -0.275042 -0.275042)
							(end -0.3048 -0.2032)
						)
						(arc
							(start -0.3048 0.2032)
							(mid -0.275042 0.275042)
							(end -0.2032 0.3048)
						)
						(arc
							(start 0.2032 0.3048)
							(mid 0.275042 0.275042)
							(end 0.3048 0.2032)
						)
					)
					(width 0)
					(fill yes)
				)
			)
		)
		(pad "2" smd custom
			(at 0 0.4445 270)
			(size 0.1524 0.1524)
			(layers "F.Cu" "F.Mask" "F.Paste")
			(net "GND")
			(options
				(clearance outline)
				(anchor circle)
			)
			(primitives
				(gr_poly
					(pts
						(arc
							(start 0.3048 -0.2032)
							(mid 0.275042 -0.275042)
							(end 0.2032 -0.3048)
						)
						(arc
							(start -0.2032 -0.3048)
							(mid -0.275042 -0.275042)
							(end -0.3048 -0.2032)
						)
						(arc
							(start -0.3048 0.2032)
							(mid -0.275042 0.275042)
							(end -0.2032 0.3048)
						)
						(arc
							(start 0.2032 0.3048)
							(mid 0.275042 0.275042)
							(end 0.3048 0.2032)
						)
					)
					(width 0)
					(fill yes)
				)
			)
		)
	)
	(footprint ""
		(layer "F.Cu")
		(at 39.37 -80.264)
		(property "Reference" "PC38"
			(at 0 0 0)
			(layer "F.SilkS")
			(hide yes)
			(effects
				(font
					(size 1.27 1.27)
				)
			)
		)
		(property "Value" "SC10U16V5KX-1-GP"
			(at -0.0762 -6.1214 0)
			(unlocked yes)
			(layer "F.Fab")
			(hide yes)
			(effects
				(font
					(size 1.016 1.016)
					(thickness 0.1524)
				)
			)
		)
		(property "Device Type" "C805H54"
			(at -0.0762 -8.1534 0)
			(unlocked yes)
			(layer "F.Fab")
			(hide yes)
			(effects
				(font
					(size 1.016 1.016)
					(thickness 0.1524)
				)
			)
		)
		(duplicate_pad_numbers_are_jumpers no)
		(fp_line
			(start 0.635 0)
			(end -0.635 0)
			(stroke
				(width 0.508)
				(type default)
			)
			(layer "F.SilkS")
		)
		(fp_rect
			(start -0.9652 1.778)
			(end 0.9652 -1.778)
			(stroke
				(width 0)
				(type default)
			)
			(fill no)
			(layer "F.CrtYd")
		)
		(fp_poly
			(pts
				(xy -0.9652 -1.778) (xy 0.9652 -1.778) (xy 0.9652 1.778) (xy -0.9652 1.778)
			)
			(stroke
				(width 0)
				(type default)
			)
			(fill no)
			(layer "F.Fab")
		)
		(pad "1" smd rect
			(at 0 -0.9652)
			(size 1.397 1.143)
			(layers "F.Cu" "F.Mask" "F.Paste")
			(net "P3V3_DEV_VIN")
		)
		(pad "2" smd rect
			(at 0 0.9652)
			(size 1.397 1.143)
			(layers "F.Cu" "F.Mask" "F.Paste")
			(net "GND")
		)
	)
)
